(kicad_pcb
	(version 20260206)
	(generator "pcbnew")
	(generator_version "10.0")
	(general
		(thickness 1.6)
		(legacy_teardrops no)
	)
	(paper "A4")
	(title_block
		(title "Wiwynn_Tioga_Pass_MB.brd")
		(comment 1 "Tioga Pass / footprints 2566-2572 of 4770")
	)
	(layers
		(0 "F.Cu" signal "TOP")
		(4 "In1.Cu" signal "L2GND")
		(6 "In2.Cu" signal "L3")
		(8 "In3.Cu" signal "L4GND")
		(10 "In4.Cu" signal "L5")
		(12 "In5.Cu" signal "L6GND")
		(14 "In6.Cu" signal "L7VCC")
		(16 "In7.Cu" signal "L8VCC")
		(18 "In8.Cu" signal "L9GND")
		(20 "In9.Cu" signal "L10")
		(22 "In10.Cu" signal "L11GND")
		(24 "In11.Cu" signal "L12")
		(26 "In12.Cu" signal "L13GND")
		(2 "B.Cu" signal "BOTTOM")
		(9 "F.Adhes" user "F.Adhesive")
		(11 "B.Adhes" user "B.Adhesive")
		(13 "F.Paste" user "Package Geometry/Pastemask Top")
		(15 "B.Paste" user "Package Geometry/Pastemask Bottom")
		(5 "F.SilkS" user "Ref Des/Silkscreen Top")
		(7 "B.SilkS" user "Ref Des/Silkscreen Bottom")
		(1 "F.Mask" user "Board Geometry/Soldermask Top")
		(3 "B.Mask" user "Board Geometry/Soldermask Bottom")
		(17 "Dwgs.User" user "User.Drawings")
		(19 "Cmts.User" user "User.Comments")
		(21 "Eco1.User" user "User.Eco1")
		(23 "Eco2.User" user "User.Eco2")
		(25 "Edge.Cuts" user "Board Geometry/Outline")
		(27 "Margin" user)
		(31 "F.CrtYd" user "Package Geometry/Place Bound Top")
		(29 "B.CrtYd" user "Package Geometry/Place Bound Bottom")
		(35 "F.Fab" user "Ref Des/Assembly Top")
		(33 "B.Fab" user "Ref Des/Assembly Bottom")
	)
	(footprint ""
		(layer "B.Cu")
		(at 16.82242 -107.94492 90)
		(property "Reference" "C9N2"
			(at 0 0 90)
			(layer "B.SilkS")
			(hide yes)
			(effects
				(font
					(size 1.27 1.27)
				)
				(justify mirror)
			)
		)
		(property "Value" ""
			(at 0 0 90)
			(layer "B.Fab")
			(effects
				(font
					(size 1.27 1.27)
				)
				(justify mirror)
			)
		)
		(duplicate_pad_numbers_are_jumpers no)
		(fp_poly
			(pts
				(xy -0.3048 -0.1016) (xy -0.3048 0.9906) (xy 0.3048 0.9906) (xy 0.3048 -0.1016)
			)
			(stroke
				(width 0)
				(type default)
			)
			(fill no)
			(layer "B.CrtYd")
		)
		(fp_line
			(start 0.3048 -0.1016)
			(end 0.3048 0.9906)
			(stroke
				(width 0.1)
				(type default)
			)
			(layer "B.Fab")
		)
		(fp_line
			(start -0.3048 -0.1016)
			(end 0.3048 -0.1016)
			(stroke
				(width 0.1)
				(type default)
			)
			(layer "B.Fab")
		)
		(fp_line
			(start 0.3048 0.9906)
			(end -0.3048 0.9906)
			(stroke
				(width 0.1)
				(type default)
			)
			(layer "B.Fab")
		)
		(fp_line
			(start -0.3048 0.9906)
			(end -0.3048 -0.1016)
			(stroke
				(width 0.1)
				(type default)
			)
			(layer "B.Fab")
		)
		(pad "1" smd rect
			(at 0 0 270)
			(size 0.508 0.508)
			(layers "B.Cu" "B.Mask" "B.Paste")
			(net "P3E_CPU1_PE3_MP_C_TXN<10>")
		)
		(pad "2" smd rect
			(at 0 0.889 270)
			(size 0.508 0.508)
			(layers "B.Cu" "B.Mask" "B.Paste")
			(net "P3E_CPU1_PE3_MP_TXN<10>")
		)
		(zone
			(layer "B.Cu")
			(hatch none 0.5)
			(connect_pads
				(clearance 0)
			)
			(min_thickness 0.25)
			(keepout
				(tracks allowed)
				(vias not_allowed)
				(pads allowed)
				(copperpour not_allowed)
				(footprints allowed)
			)
			(placement
				(enabled no)
				(sheetname "")
			)
			(fill
				(thermal_gap 0.5)
				(thermal_bridge_width 0.5)
				(island_removal_mode 0)
			)
			(polygon
				(pts
					(xy 17.07642 -108.19892) (xy 17.07642 -107.69092) (xy 17.45742 -107.69092) (xy 17.45742 -108.19892)
				)
			)
		)
		(zone
			(layer "B.Cu")
			(hatch none 0.5)
			(connect_pads
				(clearance 0)
			)
			(min_thickness 0.25)
			(keepout
				(tracks not_allowed)
				(vias allowed)
				(pads allowed)
				(copperpour not_allowed)
				(footprints allowed)
			)
			(placement
				(enabled no)
				(sheetname "")
			)
			(fill
				(thermal_gap 0.5)
				(thermal_bridge_width 0.5)
				(island_removal_mode 0)
			)
			(polygon
				(pts
					(xy 17.45742 -108.19892) (xy 17.45742 -107.69092) (xy 17.07642 -107.69092) (xy 17.07642 -108.19892)
				)
			)
		)
	)
	(footprint ""
		(layer "B.Cu")
		(at 323.758306 -29.812742 -90)
		(property "Reference" "R3R16"
			(at 0 0 90)
			(layer "B.SilkS")
			(hide yes)
			(effects
				(font
					(size 1.27 1.27)
				)
				(justify mirror)
			)
		)
		(property "Value" ""
			(at 0 0 90)
			(layer "B.Fab")
			(effects
				(font
					(size 1.27 1.27)
				)
				(justify mirror)
			)
		)
		(duplicate_pad_numbers_are_jumpers no)
		(fp_poly
			(pts
				(xy 0.2794 -0.1016) (xy -0.2794 -0.1016) (xy -0.2794 0.9906) (xy 0.2794 0.9906)
			)
			(stroke
				(width 0)
				(type default)
			)
			(fill no)
			(layer "B.CrtYd")
		)
		(fp_line
			(start -0.2794 0.9906)
			(end -0.2794 -0.1016)
			(stroke
				(width 0.1)
				(type default)
			)
			(layer "B.Fab")
		)
		(fp_line
			(start 0.2794 0.9906)
			(end -0.2794 0.9906)
			(stroke
				(width 0.1)
				(type default)
			)
			(layer "B.Fab")
		)
		(fp_line
			(start -0.2794 -0.1016)
			(end 0.2794 -0.1016)
			(stroke
				(width 0.1)
				(type default)
			)
			(layer "B.Fab")
		)
		(fp_line
			(start 0.2794 -0.1016)
			(end 0.2794 0.9906)
			(stroke
				(width 0.1)
				(type default)
			)
			(layer "B.Fab")
		)
		(pad "1" smd rect
			(at 0 0 90)
			(size 0.508 0.508)
			(layers "B.Cu" "B.Mask" "B.Paste")
			(net "PVPP_ABC")
		)
		(pad "2" smd rect
			(at 0 0.889 90)
			(size 0.508 0.508)
			(layers "B.Cu" "B.Mask" "B.Paste")
			(net "RST_CD_CPU0_POR_N")
		)
		(zone
			(layer "B.Cu")
			(hatch none 0.5)
			(connect_pads
				(clearance 0)
			)
			(min_thickness 0.25)
			(keepout
				(tracks not_allowed)
				(vias allowed)
				(pads allowed)
				(copperpour not_allowed)
				(footprints allowed)
			)
			(placement
				(enabled no)
				(sheetname "")
			)
			(fill
				(thermal_gap 0.5)
				(thermal_bridge_width 0.5)
				(island_removal_mode 0)
			)
			(polygon
				(pts
					(xy 323.123306 -29.558742) (xy 323.123306 -30.066742) (xy 323.504306 -30.066742) (xy 323.504306 -29.558742)
				)
			)
		)
		(zone
			(layer "B.Cu")
			(hatch none 0.5)
			(connect_pads
				(clearance 0)
			)
			(min_thickness 0.25)
			(keepout
				(tracks allowed)
				(vias not_allowed)
				(pads allowed)
				(copperpour not_allowed)
				(footprints allowed)
			)
			(placement
				(enabled no)
				(sheetname "")
			)
			(fill
				(thermal_gap 0.5)
				(thermal_bridge_width 0.5)
				(island_removal_mode 0)
			)
			(polygon
				(pts
					(xy 323.504306 -29.558742) (xy 323.504306 -30.066742) (xy 323.123306 -30.066742) (xy 323.123306 -29.558742)
				)
			)
		)
	)
	(footprint ""
		(layer "B.Cu")
		(at 83.856068 -8.1534 -90)
		(property "Reference" "C8U6"
			(at -1.848866 0.752348 270)
			(unlocked yes)
			(layer "B.SilkS")
			(effects
				(font
					(size 1.27 0.9652)
					(thickness 0.1524)
				)
				(justify mirror)
			)
		)
		(property "Value" ""
			(at 0 0 90)
			(layer "B.Fab")
			(effects
				(font
					(size 1.27 1.27)
				)
				(justify mirror)
			)
		)
		(duplicate_pad_numbers_are_jumpers no)
		(fp_rect
			(start 0.500126 1.598422)
			(end -0.500126 -0.201422)
			(stroke
				(width 0)
				(type default)
			)
			(fill no)
			(layer "B.CrtYd")
		)
		(fp_line
			(start -0.500126 1.598422)
			(end 0.500126 1.598422)
			(stroke
				(width 0.1)
				(type default)
			)
			(layer "B.Fab")
		)
		(fp_line
			(start 0.500126 1.598422)
			(end 0.500126 -0.201422)
			(stroke
				(width 0.1)
				(type default)
			)
			(layer "B.Fab")
		)
		(fp_line
			(start -0.500126 -0.201422)
			(end -0.500126 1.598422)
			(stroke
				(width 0.1)
				(type default)
			)
			(layer "B.Fab")
		)
		(fp_line
			(start 0.500126 -0.201422)
			(end -0.500126 -0.201422)
			(stroke
				(width 0.1)
				(type default)
			)
			(layer "B.Fab")
		)
		(pad "1" smd rect
			(at 0 0 180)
			(size 0.889 0.9906)
			(layers "B.Cu" "B.Mask" "B.Paste")
			(net "PVDDQ_GHJ")
		)
		(pad "2" smd rect
			(at 0 1.397 180)
			(size 0.889 0.9906)
			(layers "B.Cu" "B.Mask" "B.Paste")
			(net "GND")
		)
		(zone
			(layer "B.Cu")
			(hatch none 0.5)
			(connect_pads
				(clearance 0)
			)
			(min_thickness 0.25)
			(keepout
				(tracks not_allowed)
				(vias allowed)
				(pads allowed)
				(copperpour not_allowed)
				(footprints allowed)
			)
			(placement
				(enabled no)
				(sheetname "")
			)
			(fill
				(thermal_gap 0.5)
				(thermal_bridge_width 0.5)
				(island_removal_mode 0)
			)
			(polygon
				(pts
					(xy 82.903568 -7.6581) (xy 83.411568 -7.6581) (xy 83.411568 -8.6487) (xy 82.903568 -8.6487)
				)
			)
		)
		(zone
			(layer "B.Cu")
			(hatch none 0.5)
			(connect_pads
				(clearance 0)
			)
			(min_thickness 0.25)
			(keepout
				(tracks allowed)
				(vias not_allowed)
				(pads allowed)
				(copperpour not_allowed)
				(footprints allowed)
			)
			(placement
				(enabled no)
				(sheetname "")
			)
			(fill
				(thermal_gap 0.5)
				(thermal_bridge_width 0.5)
				(island_removal_mode 0)
			)
			(polygon
				(pts
					(xy 82.903568 -7.6581) (xy 83.411568 -7.6581) (xy 83.411568 -8.6487) (xy 82.903568 -8.6487)
				)
			)
		)
	)
	(footprint ""
		(layer "B.Cu")
		(at 275.262086 -68.17614 180)
		(property "Reference" "C5P40"
			(at 0 0 0)
			(layer "B.SilkS")
			(hide yes)
			(effects
				(font
					(size 1.27 1.27)
				)
				(justify mirror)
			)
		)
		(property "Value" ""
			(at 0 0 0)
			(layer "B.Fab")
			(effects
				(font
					(size 1.27 1.27)
				)
				(justify mirror)
			)
		)
		(duplicate_pad_numbers_are_jumpers no)
		(fp_poly
			(pts
				(xy 0.7239 -0.2159) (xy -0.7239 -0.2159) (xy -0.7239 1.9939) (xy 0.7239 1.9939)
			)
			(stroke
				(width 0)
				(type default)
			)
			(fill no)
			(layer "B.CrtYd")
		)
		(fp_line
			(start 0.7239 1.9939)
			(end -0.7239 1.9939)
			(stroke
				(width 0.1)
				(type default)
			)
			(layer "B.Fab")
		)
		(fp_line
			(start 0.7239 -0.2159)
			(end 0.7239 1.9939)
			(stroke
				(width 0.1)
				(type default)
			)
			(layer "B.Fab")
		)
		(fp_line
			(start -0.7239 1.9939)
			(end -0.7239 -0.2159)
			(stroke
				(width 0.1)
				(type default)
			)
			(layer "B.Fab")
		)
		(fp_line
			(start -0.7239 -0.2159)
			(end 0.7239 -0.2159)
			(stroke
				(width 0.1)
				(type default)
			)
			(layer "B.Fab")
		)
		(pad "1" smd rect
			(at 0 0)
			(size 1.27 1.016)
			(layers "B.Cu" "B.Mask" "B.Paste")
			(net "PVCCIN_CPU0")
		)
		(pad "2" smd rect
			(at 0 1.778)
			(size 1.27 1.016)
			(layers "B.Cu" "B.Mask" "B.Paste")
			(net "GND")
		)
		(zone
			(layer "B.Cu")
			(hatch none 0.5)
			(connect_pads
				(clearance 0)
			)
			(min_thickness 0.25)
			(keepout
				(tracks not_allowed)
				(vias allowed)
				(pads allowed)
				(copperpour not_allowed)
				(footprints allowed)
			)
			(placement
				(enabled no)
				(sheetname "")
			)
			(fill
				(thermal_gap 0.5)
				(thermal_bridge_width 0.5)
				(island_removal_mode 0)
			)
			(polygon
				(pts
					(xy 274.627086 -68.68414) (xy 275.897086 -68.68414) (xy 275.897086 -69.44614) (xy 274.627086 -69.44614)
				)
			)
		)
	)
	(footprint ""
		(layer "B.Cu")
		(at 477.698816 -146.359372)
		(property "Reference" "R6W10"
			(at 0.8382 -0.67818 0)
			(unlocked yes)
			(layer "B.SilkS")
			(effects
				(font
					(size 0.4064 0.254)
					(thickness 0.1524)
				)
				(justify left mirror)
			)
		)
		(property "Value" ""
			(at 0 0 0)
			(layer "B.Fab")
			(effects
				(font
					(size 1.27 1.27)
				)
				(justify mirror)
			)
		)
		(duplicate_pad_numbers_are_jumpers no)
		(fp_poly
			(pts
				(xy 0.2794 -0.1016) (xy -0.2794 -0.1016) (xy -0.2794 0.9906) (xy 0.2794 0.9906)
			)
			(stroke
				(width 0)
				(type default)
			)
			(fill no)
			(layer "B.CrtYd")
		)
		(fp_line
			(start -0.2794 -0.1016)
			(end 0.2794 -0.1016)
			(stroke
				(width 0.1)
				(type default)
			)
			(layer "B.Fab")
		)
		(fp_line
			(start -0.2794 0.9906)
			(end -0.2794 -0.1016)
			(stroke
				(width 0.1)
				(type default)
			)
			(layer "B.Fab")
		)
		(fp_line
			(start 0.2794 -0.1016)
			(end 0.2794 0.9906)
			(stroke
				(width 0.1)
				(type default)
			)
			(layer "B.Fab")
		)
		(fp_line
			(start 0.2794 0.9906)
			(end -0.2794 0.9906)
			(stroke
				(width 0.1)
				(type default)
			)
			(layer "B.Fab")
		)
		(pad "1" smd rect
			(at 0 0 180)
			(size 0.508 0.508)
			(layers "B.Cu" "B.Mask" "B.Paste")
			(net "P3V3_STBY")
		)
		(pad "2" smd rect
			(at 0 0.889 180)
			(size 0.508 0.508)
			(layers "B.Cu" "B.Mask" "B.Paste")
			(net "PCA9555_INT_N")
		)
		(zone
			(layer "B.Cu")
			(hatch none 0.5)
			(connect_pads
				(clearance 0)
			)
			(min_thickness 0.25)
			(keepout
				(tracks allowed)
				(vias not_allowed)
				(pads allowed)
				(copperpour not_allowed)
				(footprints allowed)
			)
			(placement
				(enabled no)
				(sheetname "")
			)
			(fill
				(thermal_gap 0.5)
				(thermal_bridge_width 0.5)
				(island_removal_mode 0)
			)
			(polygon
				(pts
					(xy 477.952816 -146.105372) (xy 477.444816 -146.105372) (xy 477.444816 -145.724372) (xy 477.952816 -145.724372)
				)
			)
		)
		(zone
			(layer "B.Cu")
			(hatch none 0.5)
			(connect_pads
				(clearance 0)
			)
			(min_thickness 0.25)
			(keepout
				(tracks not_allowed)
				(vias allowed)
				(pads allowed)
				(copperpour not_allowed)
				(footprints allowed)
			)
			(placement
				(enabled no)
				(sheetname "")
			)
			(fill
				(thermal_gap 0.5)
				(thermal_bridge_width 0.5)
				(island_removal_mode 0)
			)
			(polygon
				(pts
					(xy 477.952816 -145.724372) (xy 477.444816 -145.724372) (xy 477.444816 -146.105372) (xy 477.952816 -146.105372)
				)
			)
		)
	)
	(footprint ""
		(layer "B.Cu")
		(at 371.060472 -93.952822 180)
		(property "Reference" "R3N15"
			(at 0.8382 -0.67818 180)
			(unlocked yes)
			(layer "B.SilkS")
			(effects
				(font
					(size 0.4064 0.254)
					(thickness 0.1524)
				)
				(justify left mirror)
			)
		)
		(property "Value" ""
			(at 0 0 0)
			(layer "B.Fab")
			(effects
				(font
					(size 1.27 1.27)
				)
				(justify mirror)
			)
		)
		(duplicate_pad_numbers_are_jumpers no)
		(fp_poly
			(pts
				(xy 0.2794 -0.1016) (xy -0.2794 -0.1016) (xy -0.2794 0.9906) (xy 0.2794 0.9906)
			)
			(stroke
				(width 0)
				(type default)
			)
			(fill no)
			(layer "B.CrtYd")
		)
		(fp_line
			(start 0.2794 0.9906)
			(end -0.2794 0.9906)
			(stroke
				(width 0.1)
				(type default)
			)
			(layer "B.Fab")
		)
		(fp_line
			(start 0.2794 -0.1016)
			(end 0.2794 0.9906)
			(stroke
				(width 0.1)
				(type default)
			)
			(layer "B.Fab")
		)
		(fp_line
			(start -0.2794 0.9906)
			(end -0.2794 -0.1016)
			(stroke
				(width 0.1)
				(type default)
			)
			(layer "B.Fab")
		)
		(fp_line
			(start -0.2794 -0.1016)
			(end 0.2794 -0.1016)
			(stroke
				(width 0.1)
				(type default)
			)
			(layer "B.Fab")
		)
		(pad "1" smd rect
			(at 0 0)
			(size 0.508 0.508)
			(layers "B.Cu" "B.Mask" "B.Paste")
			(net "P1V05_PCH_STBY")
		)
		(pad "2" smd rect
			(at 0 0.889)
			(size 0.508 0.508)
			(layers "B.Cu" "B.Mask" "B.Paste")
			(net "FM_PRSNT_2_4_N")
		)
		(zone
			(layer "B.Cu")
			(hatch none 0.5)
			(connect_pads
				(clearance 0)
			)
			(min_thickness 0.25)
			(keepout
				(tracks not_allowed)
				(vias allowed)
				(pads allowed)
				(copperpour not_allowed)
				(footprints allowed)
			)
			(placement
				(enabled no)
				(sheetname "")
			)
			(fill
				(thermal_gap 0.5)
				(thermal_bridge_width 0.5)
				(island_removal_mode 0)
			)
			(polygon
				(pts
					(xy 370.806472 -94.587822) (xy 371.314472 -94.587822) (xy 371.314472 -94.206822) (xy 370.806472 -94.206822)
				)
			)
		)
		(zone
			(layer "B.Cu")
			(hatch none 0.5)
			(connect_pads
				(clearance 0)
			)
			(min_thickness 0.25)
			(keepout
				(tracks allowed)
				(vias not_allowed)
				(pads allowed)
				(copperpour not_allowed)
				(footprints allowed)
			)
			(placement
				(enabled no)
				(sheetname "")
			)
			(fill
				(thermal_gap 0.5)
				(thermal_bridge_width 0.5)
				(island_removal_mode 0)
			)
			(polygon
				(pts
					(xy 370.806472 -94.206822) (xy 371.314472 -94.206822) (xy 371.314472 -94.587822) (xy 370.806472 -94.587822)
				)
			)
		)
	)
	(footprint ""
		(layer "B.Cu")
		(at 402.13026 -54.24678)
		(property "Reference" "C3T4"
			(at 0 0 0)
			(layer "B.SilkS")
			(hide yes)
			(effects
				(font
					(size 1.27 1.27)
				)
				(justify mirror)
			)
		)
		(property "Value" ""
			(at 0 0 0)
			(layer "B.Fab")
			(effects
				(font
					(size 1.27 1.27)
				)
				(justify mirror)
			)
		)
		(duplicate_pad_numbers_are_jumpers no)
		(fp_poly
			(pts
				(xy -0.3048 -0.1016) (xy -0.3048 0.9906) (xy 0.3048 0.9906) (xy 0.3048 -0.1016)
			)
			(stroke
				(width 0)
				(type default)
			)
			(fill no)
			(layer "B.CrtYd")
		)
		(fp_line
			(start -0.3048 -0.1016)
			(end 0.3048 -0.1016)
			(stroke
				(width 0.1)
				(type default)
			)
			(layer "B.Fab")
		)
		(fp_line
			(start -0.3048 0.9906)
			(end -0.3048 -0.1016)
			(stroke
				(width 0.1)
				(type default)
			)
			(layer "B.Fab")
		)
		(fp_line
			(start 0.3048 -0.1016)
			(end 0.3048 0.9906)
			(stroke
				(width 0.1)
				(type default)
			)
			(layer "B.Fab")
		)
		(fp_line
			(start 0.3048 0.9906)
			(end -0.3048 0.9906)
			(stroke
				(width 0.1)
				(type default)
			)
			(layer "B.Fab")
		)
		(pad "1" smd rect
			(at 0 0 180)
			(size 0.508 0.508)
			(layers "B.Cu" "B.Mask" "B.Paste")
			(net "P3V3_STBY")
		)
		(pad "2" smd rect
			(at 0 0.889 180)
			(size 0.508 0.508)
			(layers "B.Cu" "B.Mask" "B.Paste")
			(net "GND")
		)
		(zone
			(layer "B.Cu")
			(hatch none 0.5)
			(connect_pads
				(clearance 0)
			)
			(min_thickness 0.25)
			(keepout
				(tracks allowed)
				(vias not_allowed)
				(pads allowed)
				(copperpour not_allowed)
				(footprints allowed)
			)
			(placement
				(enabled no)
				(sheetname "")
			)
			(fill
				(thermal_gap 0.5)
				(thermal_bridge_width 0.5)
				(island_removal_mode 0)
			)
			(polygon
				(pts
					(xy 402.38426 -53.99278) (xy 401.87626 -53.99278) (xy 401.87626 -53.61178) (xy 402.38426 -53.61178)
				)
			)
		)
		(zone
			(layer "B.Cu")
			(hatch none 0.5)
			(connect_pads
				(clearance 0)
			)
			(min_thickness 0.25)
			(keepout
				(tracks not_allowed)
				(vias allowed)
				(pads allowed)
				(copperpour not_allowed)
				(footprints allowed)
			)
			(placement
				(enabled no)
				(sheetname "")
			)
			(fill
				(thermal_gap 0.5)
				(thermal_bridge_width 0.5)
				(island_removal_mode 0)
			)
			(polygon
				(pts
					(xy 402.38426 -53.61178) (xy 401.87626 -53.61178) (xy 401.87626 -53.99278) (xy 402.38426 -53.99278)
				)
			)
		)
	)
)
